# S9S_MB_2U (Grand Teton) — schematic netlist excerpt (pin names and nets, part order shuffled) for the footprints in the layout excerpt that follows; sources: Cadence DE-HDL packaged netlist, KiCad conversion of 03242023_DA0F0TMBIJ0_F0T_Motherboard_J_brd_V01_OCP.brd

C53  Q_CAP  2.2UF 6.3V 20% X6S  pkg C0402  page 99 : A = P3V3_AUX ; B = GND
R1267  Q_RES  1K 1% CHIP  pkg 0402LF  page 208 : A = PU_CK440_SHFT_LD_N ; B = GND

(kicad_pcb
	(version 20260206)
	(generator "pcbnew")
	(generator_version "10.0")
	(general
		(thickness 1.6)
		(legacy_teardrops no)
	)
	(paper "A4")
	(title_block
		(title "03242023_DA0F0TMBIJ0_F0T_Motherboard_J_brd_V01_OCP.brd")
		(comment 1 "Grand Teton / footprints 4255-4256 of 6105")
	)
	(layers
		(0 "F.Cu" signal "TOP")
		(4 "In1.Cu" signal "GND")
		(6 "In2.Cu" signal "IN1")
		(8 "In3.Cu" signal "GND1")
		(10 "In4.Cu" signal "IN2")
		(12 "In5.Cu" signal "GND2")
		(14 "In6.Cu" signal "IN3")
		(16 "In7.Cu" signal "GND3")
		(18 "In8.Cu" signal "VCC")
		(20 "In9.Cu" signal "VCC1")
		(22 "In10.Cu" signal "GND4")
		(24 "In11.Cu" signal "IN4")
		(26 "In12.Cu" signal "GND5")
		(28 "In13.Cu" signal "IN5")
		(30 "In14.Cu" signal "GND6")
		(32 "In15.Cu" signal "IN6")
		(34 "In16.Cu" signal "GND7")
		(2 "B.Cu" signal "BOTTOM")
		(9 "F.Adhes" user "F.Adhesive")
		(11 "B.Adhes" user "B.Adhesive")
		(13 "F.Paste" user "Package Geometry/Pastemask Top")
		(15 "B.Paste" user "Package Geometry/Pastemask Bottom")
		(5 "F.SilkS" user "Ref Des/Silkscreen Top")
		(7 "B.SilkS" user "Ref Des/Silkscreen Bottom")
		(1 "F.Mask" user "Board Geometry/Soldermask Top")
		(3 "B.Mask" user "Board Geometry/Soldermask Bottom")
		(17 "Dwgs.User" user "User.Drawings")
		(19 "Cmts.User" user "User.Comments")
		(21 "Eco1.User" user "User.Eco1")
		(23 "Eco2.User" user "User.Eco2")
		(25 "Edge.Cuts" user "Board Geometry/Outline")
		(27 "Margin" user)
		(31 "F.CrtYd" user "Package Geometry/Place Bound Top")
		(29 "B.CrtYd" user "Package Geometry/Place Bound Bottom")
		(35 "F.Fab" user "Ref Des/Assembly Top")
		(33 "B.Fab" user "Ref Des/Assembly Bottom")
	)
	(footprint ""
		(layer "B.Cu")
		(at 254.824484 -107.361228 180)
		(property "Reference" "R1267"
			(at 0 0 0)
			(layer "B.SilkS")
			(hide yes)
			(effects
				(font
					(size 1.27 1.27)
				)
				(justify mirror)
			)
		)
		(property "Value" ""
			(at 0 0 0)
			(layer "B.Fab")
			(effects
				(font
					(size 1.27 1.27)
				)
				(justify mirror)
			)
		)
		(duplicate_pad_numbers_are_jumpers no)
		(fp_line
			(start 0.7874 0.4064)
			(end 0.7874 -0.4064)
			(stroke
				(width 0.1524)
				(type default)
			)
			(layer "B.SilkS")
		)
		(fp_line
			(start 0.7874 -0.4064)
			(end -0.7874 -0.4064)
			(stroke
				(width 0.1524)
				(type default)
			)
			(layer "B.SilkS")
		)
		(fp_line
			(start -0.7874 0.4064)
			(end 0.7874 0.4064)
			(stroke
				(width 0.1524)
				(type default)
			)
			(layer "B.SilkS")
		)
		(fp_line
			(start -0.7874 -0.4064)
			(end -0.7874 0.4064)
			(stroke
				(width 0.1524)
				(type default)
			)
			(layer "B.SilkS")
		)
		(fp_line
			(start 0.67945 0.3048)
			(end 0.67945 -0.305054)
			(stroke
				(width 0.1)
				(type default)
			)
			(layer "B.Fab")
		)
		(fp_line
			(start 0.67945 -0.305054)
			(end 0.12065 -0.305054)
			(stroke
				(width 0.1)
				(type default)
			)
			(layer "B.Fab")
		)
		(fp_line
			(start 0.12065 0.3048)
			(end 0.67945 0.3048)
			(stroke
				(width 0.1)
				(type default)
			)
			(layer "B.Fab")
		)
		(fp_line
			(start 0.12065 0.2794)
			(end 0.12065 0.3048)
			(stroke
				(width 0.1)
				(type default)
			)
			(layer "B.Fab")
		)
		(fp_line
			(start 0.12065 -0.2794)
			(end -0.12065 -0.2794)
			(stroke
				(width 0.1)
				(type default)
			)
			(layer "B.Fab")
		)
		(fp_line
			(start 0.12065 -0.305054)
			(end 0.12065 -0.2794)
			(stroke
				(width 0.1)
				(type default)
			)
			(layer "B.Fab")
		)
		(fp_line
			(start -0.120396 0.3048)
			(end -0.120396 0.2794)
			(stroke
				(width 0.1)
				(type default)
			)
			(layer "B.Fab")
		)
		(fp_line
			(start -0.120396 0.2794)
			(end 0.12065 0.2794)
			(stroke
				(width 0.1)
				(type default)
			)
			(layer "B.Fab")
		)
		(fp_line
			(start -0.12065 -0.2794)
			(end -0.12065 -0.3048)
			(stroke
				(width 0.1)
				(type default)
			)
			(layer "B.Fab")
		)
		(fp_line
			(start -0.12065 -0.3048)
			(end -0.67945 -0.3048)
			(stroke
				(width 0.1)
				(type default)
			)
			(layer "B.Fab")
		)
		(fp_line
			(start -0.67945 0.3048)
			(end -0.120396 0.3048)
			(stroke
				(width 0.1)
				(type default)
			)
			(layer "B.Fab")
		)
		(fp_line
			(start -0.67945 -0.3048)
			(end -0.67945 0.3048)
			(stroke
				(width 0.1)
				(type default)
			)
			(layer "B.Fab")
		)
		(pad "1" smd circle
			(at 0.40005 0)
			(size 0 0)
			(layers "B.Cu" "B.Mask" "B.Paste")
			(net "PU_CK440_SHFT_LD_N")
		)
		(pad "2" smd circle
			(at -0.40005 0)
			(size 0 0)
			(layers "B.Cu" "B.Mask" "B.Paste")
			(net "GND")
		)
	)
	(footprint ""
		(layer "B.Cu")
		(at 60.926218 -319.393824 180)
		(property "Reference" "C53"
			(at 0 0 0)
			(layer "B.SilkS")
			(hide yes)
			(effects
				(font
					(size 1.27 1.27)
				)
				(justify mirror)
			)
		)
		(property "Value" ""
			(at 0 0 0)
			(layer "B.Fab")
			(effects
				(font
					(size 1.27 1.27)
				)
				(justify mirror)
			)
		)
		(duplicate_pad_numbers_are_jumpers no)
		(fp_line
			(start 0.7874 0.4064)
			(end 0.7874 -0.4064)
			(stroke
				(width 0.1524)
				(type default)
			)
			(layer "B.SilkS")
		)
		(fp_line
			(start 0.7874 -0.4064)
			(end -0.7874 -0.4064)
			(stroke
				(width 0.1524)
				(type default)
			)
			(layer "B.SilkS")
		)
		(fp_line
			(start -0.7874 0.4064)
			(end 0.7874 0.4064)
			(stroke
				(width 0.1524)
				(type default)
			)
			(layer "B.SilkS")
		)
		(fp_line
			(start -0.7874 -0.4064)
			(end -0.7874 0.4064)
			(stroke
				(width 0.1524)
				(type default)
			)
			(layer "B.SilkS")
		)
		(fp_line
			(start 0.67945 0.3048)
			(end 0.67945 -0.305054)
			(stroke
				(width 0.1)
				(type default)
			)
			(layer "B.Fab")
		)
		(fp_line
			(start 0.67945 -0.305054)
			(end 0.12065 -0.305054)
			(stroke
				(width 0.1)
				(type default)
			)
			(layer "B.Fab")
		)
		(fp_line
			(start 0.12065 0.3048)
			(end 0.67945 0.3048)
			(stroke
				(width 0.1)
				(type default)
			)
			(layer "B.Fab")
		)
		(fp_line
			(start 0.12065 0.2794)
			(end 0.12065 0.3048)
			(stroke
				(width 0.1)
				(type default)
			)
			(layer "B.Fab")
		)
		(fp_line
			(start 0.12065 -0.2794)
			(end -0.12065 -0.2794)
			(stroke
				(width 0.1)
				(type default)
			)
			(layer "B.Fab")
		)
		(fp_line
			(start 0.12065 -0.305054)
			(end 0.12065 -0.2794)
			(stroke
				(width 0.1)
				(type default)
			)
			(layer "B.Fab")
		)
		(fp_line
			(start -0.120396 0.3048)
			(end -0.120396 0.2794)
			(stroke
				(width 0.1)
				(type default)
			)
			(layer "B.Fab")
		)
		(fp_line
			(start -0.120396 0.2794)
			(end 0.12065 0.2794)
			(stroke
				(width 0.1)
				(type default)
			)
			(layer "B.Fab")
		)
		(fp_line
			(start -0.12065 -0.2794)
			(end -0.12065 -0.3048)
			(stroke
				(width 0.1)
				(type default)
			)
			(layer "B.Fab")
		)
		(fp_line
			(start -0.12065 -0.3048)
			(end -0.67945 -0.3048)
			(stroke
				(width 0.1)
				(type default)
			)
			(layer "B.Fab")
		)
		(fp_line
			(start -0.67945 0.3048)
			(end -0.120396 0.3048)
			(stroke
				(width 0.1)
				(type default)
			)
			(layer "B.Fab")
		)
		(fp_line
			(start -0.67945 -0.3048)
			(end -0.67945 0.3048)
			(stroke
				(width 0.1)
				(type default)
			)
			(layer "B.Fab")
		)
		(pad "1" smd circle
			(at 0.40005 0)
			(size 0 0)
			(layers "B.Cu" "B.Mask" "B.Paste")
			(net "P3V3_AUX")
		)
		(pad "2" smd circle
			(at -0.40005 0)
			(size 0 0)
			(layers "B.Cu" "B.Mask" "B.Paste")
			(net "GND")
		)
	)
)
